(kicad_pcb
	(version 20221018)
	(generator pcbnew)
	(general
    (thickness 1.518)
  )
	(paper "A4")
	(title_block
    (title "Kria K26 Devboard")
    (date "2024-03-26")
    (rev "1.2.5")
    (comment 1 "www.antmicro.com")
    (comment 2 "Antmicro Ltd.")
		(comment 9 "footprint 78 of 660 (J_SOM240_2), pads 200-242 of 242")
	)
	(layers
    (0 "F.Cu" mixed)
    (1 "In1.Cu" power)
    (2 "In2.Cu" mixed)
    (3 "In3.Cu" power)
    (4 "In4.Cu" mixed)
    (5 "In5.Cu" power)
    (6 "In6.Cu" mixed)
    (31 "B.Cu" power)
    (32 "B.Adhes" user "B.Adhesive")
    (33 "F.Adhes" user "F.Adhesive")
    (34 "B.Paste" user)
    (35 "F.Paste" user)
    (36 "B.SilkS" user "B.Silkscreen")
    (37 "F.SilkS" user "F.Silkscreen")
    (38 "B.Mask" user)
    (39 "F.Mask" user)
    (40 "Dwgs.User" user "User.Drawings")
    (41 "Cmts.User" user "User.Comments")
    (42 "Eco1.User" user "User.Eco1")
    (43 "Eco2.User" user "User.Eco2")
    (44 "Edge.Cuts" user)
    (45 "Margin" user)
    (46 "B.CrtYd" user "B.Courtyard")
    (47 "F.CrtYd" user "F.Courtyard")
    (48 "B.Fab" user)
    (49 "F.Fab" user)
  )
	(footprint "kria-k26-devboard-footprints:Conn_Plug_Samtec_ADM6_4x60_ADM6-60-01.5-L-4-2-A-TR"
    (layer "F.Cu")
    (at 158.177 117.6205 -90)
    (property "Author" "Antmicro")
    (property "DNP" "DNP")
    (property "License" "Apache-2.0")
    (property "MPN" "ADM6-60-01.5-L-4-2-A-TR")
    (property "Manufacturer" "Samtec")
    (property "Sheetfile" "k26_som.kicad_sch")
    (property "Sheetname" "Xilinx K26 SOM")
    (property "dnp" "")
    (property "exclude_from_bom" "")
    (property "ki_description" "Board to Board & Mezzanine Connectors 0.635 mm AcceleRate HD High-Density 4-Row Header 60P")
    (attr exclude_from_pos_files exclude_from_bom)
    (fp_text reference "J_SOM240_2" (at -14.0505 -3.623 90) (layer "F.SilkS")
        (effects (font (size 0.7 0.7) (thickness 0.15)) (justify right bottom))
    )
    (fp_text value "ADM6-60-01.5-L-4-2-A-TR" (at 0 3.7 90) (layer "F.Fab") hide
        (effects (font (size 0.7 0.7) (thickness 0.15)) (justify right bottom))
    )
    (pad "D18" smd circle (at 7.937 1.749 270) (size 0.356 0.356) (layers "F.Cu" "F.Paste" "F.Mask")
      (net 607 "/Xilinx K26 SOM/HPB_CLK0_P") (pinfunction "D18") (pintype "passive"))
    (pad "D19" smd circle (at 7.302 1.749 270) (size 0.356 0.356) (layers "F.Cu" "F.Paste" "F.Mask")
      (net 608 "/Xilinx K26 SOM/HPB_CLK0_N") (pinfunction "D19") (pintype "passive"))
    (pad "D20" smd circle (at 6.667 1.749 270) (size 0.356 0.356) (layers "F.Cu" "F.Paste" "F.Mask")
      (net 1 "GND") (pinfunction "D20") (pintype "passive"))
    (pad "D21" smd circle (at 6.032 1.749 270) (size 0.356 0.356) (layers "F.Cu" "F.Paste" "F.Mask")
      (net 609 "/Xilinx K26 SOM/HPB04_P") (pinfunction "D21") (pintype "passive"))
    (pad "D22" smd circle (at 5.397 1.749 270) (size 0.356 0.356) (layers "F.Cu" "F.Paste" "F.Mask")
      (net 610 "/Xilinx K26 SOM/HPB04_N") (pinfunction "D22") (pintype "passive"))
    (pad "D23" smd circle (at 4.762 1.749 270) (size 0.356 0.356) (layers "F.Cu" "F.Paste" "F.Mask")
      (net 1 "GND") (pinfunction "D23") (pintype "passive"))
    (pad "D24" smd circle (at 4.127 1.749 270) (size 0.356 0.356) (layers "F.Cu" "F.Paste" "F.Mask")
      (net 611 "/Xilinx K26 SOM/HPB17_P") (pinfunction "D24") (pintype "passive"))
    (pad "D25" smd circle (at 3.492 1.749 270) (size 0.356 0.356) (layers "F.Cu" "F.Paste" "F.Mask")
      (net 612 "/Xilinx K26 SOM/HPB17_N") (pinfunction "D25") (pintype "passive"))
    (pad "D26" smd circle (at 2.857 1.749 270) (size 0.356 0.356) (layers "F.Cu" "F.Paste" "F.Mask")
      (net 1 "GND") (pinfunction "D26") (pintype "passive"))
    (pad "D27" smd circle (at 2.222 1.749 270) (size 0.356 0.356) (layers "F.Cu" "F.Paste" "F.Mask")
      (net 613 "/Xilinx K26 SOM/HPC09_P") (pinfunction "D27") (pintype "passive"))
    (pad "D28" smd circle (at 1.587 1.749 270) (size 0.356 0.356) (layers "F.Cu" "F.Paste" "F.Mask")
      (net 614 "/Xilinx K26 SOM/HPC09_N") (pinfunction "D28") (pintype "passive"))
    (pad "D29" smd circle (at 0.952 1.749 270) (size 0.356 0.356) (layers "F.Cu" "F.Paste" "F.Mask")
      (net 1 "GND") (pinfunction "D29") (pintype "passive"))
    (pad "D30" smd circle (at 0.317 1.749 270) (size 0.356 0.356) (layers "F.Cu" "F.Paste" "F.Mask")
      (net 615 "/Xilinx K26 SOM/HPC01_P") (pinfunction "D30") (pintype "passive"))
    (pad "D31" smd circle (at -0.318 1.749 270) (size 0.356 0.356) (layers "F.Cu" "F.Paste" "F.Mask")
      (net 616 "/Xilinx K26 SOM/HPC01_N") (pinfunction "D31") (pintype "passive"))
    (pad "D32" smd circle (at -0.953 1.749 270) (size 0.356 0.356) (layers "F.Cu" "F.Paste" "F.Mask")
      (net 1 "GND") (pinfunction "D32") (pintype "passive"))
    (pad "D33" smd circle (at -1.588 1.749 270) (size 0.356 0.356) (layers "F.Cu" "F.Paste" "F.Mask")
      (net 617 "/Xilinx K26 SOM/HPC00_CC_P") (pinfunction "D33") (pintype "passive"))
    (pad "D34" smd circle (at -2.223 1.749 270) (size 0.356 0.356) (layers "F.Cu" "F.Paste" "F.Mask")
      (net 618 "/Xilinx K26 SOM/HPC00_CC_N") (pinfunction "D34") (pintype "passive"))
    (pad "D35" smd circle (at -2.858 1.749 270) (size 0.356 0.356) (layers "F.Cu" "F.Paste" "F.Mask")
      (net 1 "GND") (pinfunction "D35") (pintype "passive"))
    (pad "D36" smd circle (at -3.493 1.749 270) (size 0.356 0.356) (layers "F.Cu" "F.Paste" "F.Mask")
      (net 619 "/Xilinx K26 SOM/HPC02_P") (pinfunction "D36") (pintype "passive"))
    (pad "D37" smd circle (at -4.128 1.749 270) (size 0.356 0.356) (layers "F.Cu" "F.Paste" "F.Mask")
      (net 620 "/Xilinx K26 SOM/HPC02_N") (pinfunction "D37") (pintype "passive"))
    (pad "D38" smd circle (at -4.763 1.749 270) (size 0.356 0.356) (layers "F.Cu" "F.Paste" "F.Mask")
      (net 1 "GND") (pinfunction "D38") (pintype "passive"))
    (pad "D39" smd circle (at -5.398 1.749 270) (size 0.356 0.356) (layers "F.Cu" "F.Paste" "F.Mask")
      (net 621 "/Xilinx K26 SOM/HPC04_P") (pinfunction "D39") (pintype "passive"))
    (pad "D40" smd circle (at -6.033 1.749 270) (size 0.356 0.356) (layers "F.Cu" "F.Paste" "F.Mask")
      (net 622 "/Xilinx K26 SOM/HPC04_N") (pinfunction "D40") (pintype "passive"))
    (pad "D41" smd circle (at -6.668 1.749 270) (size 0.356 0.356) (layers "F.Cu" "F.Paste" "F.Mask")
      (net 1 "GND") (pinfunction "D41") (pintype "passive"))
    (pad "D42" smd circle (at -7.303 1.749 270) (size 0.356 0.356) (layers "F.Cu" "F.Paste" "F.Mask")
      (net 623 "/Xilinx K26 SOM/VCCO_HPC_2") (pinfunction "D42") (pintype "passive"))
    (pad "D43" smd circle (at -7.938 1.749 270) (size 0.356 0.356) (layers "F.Cu" "F.Paste" "F.Mask")
      (net 1 "GND") (pinfunction "D43") (pintype "passive"))
    (pad "D44" smd circle (at -8.573 1.749 270) (size 0.356 0.356) (layers "F.Cu" "F.Paste" "F.Mask")
      (net 624 "/Xilinx K26 SOM/HDB00_CC") (pinfunction "D44") (pintype "passive"))
    (pad "D45" smd circle (at -9.208 1.749 270) (size 0.356 0.356) (layers "F.Cu" "F.Paste" "F.Mask")
      (net 625 "/Xilinx K26 SOM/HDB01") (pinfunction "D45") (pintype "passive"))
    (pad "D46" smd circle (at -9.843 1.749 270) (size 0.356 0.356) (layers "F.Cu" "F.Paste" "F.Mask")
      (net 626 "/Xilinx K26 SOM/HDB02") (pinfunction "D46") (pintype "passive"))
    (pad "D47" smd circle (at -10.478 1.749 270) (size 0.356 0.356) (layers "F.Cu" "F.Paste" "F.Mask")
      (net 1 "GND") (pinfunction "D47") (pintype "passive"))
    (pad "D48" smd circle (at -11.113 1.749 270) (size 0.356 0.356) (layers "F.Cu" "F.Paste" "F.Mask")
      (net 627 "/Xilinx K26 SOM/HDB03") (pinfunction "D48") (pintype "passive"))
    (pad "D49" smd circle (at -11.748 1.749 270) (size 0.356 0.356) (layers "F.Cu" "F.Paste" "F.Mask")
      (net 628 "/Xilinx K26 SOM/HDB04") (pinfunction "D49") (pintype "passive"))
    (pad "D50" smd circle (at -12.383 1.749 270) (size 0.356 0.356) (layers "F.Cu" "F.Paste" "F.Mask")
      (net 629 "/Xilinx K26 SOM/HDB05") (pinfunction "D50") (pintype "passive"))
    (pad "D51" smd circle (at -13.018 1.749 270) (size 0.356 0.356) (layers "F.Cu" "F.Paste" "F.Mask")
      (net 1 "GND") (pinfunction "D51") (pintype "passive"))
    (pad "D52" smd circle (at -13.653 1.749 270) (size 0.356 0.356) (layers "F.Cu" "F.Paste" "F.Mask")
      (net 630 "/Xilinx K26 SOM/HDC00_CC") (pinfunction "D52") (pintype "passive"))
    (pad "D53" smd circle (at -14.288 1.749 270) (size 0.356 0.356) (layers "F.Cu" "F.Paste" "F.Mask")
      (net 631 "/Xilinx K26 SOM/HDC01") (pinfunction "D53") (pintype "passive"))
    (pad "D54" smd circle (at -14.923 1.749 270) (size 0.356 0.356) (layers "F.Cu" "F.Paste" "F.Mask")
      (net 632 "/Xilinx K26 SOM/HDC02") (pinfunction "D54") (pintype "passive"))
    (pad "D55" smd circle (at -15.558 1.749 270) (size 0.356 0.356) (layers "F.Cu" "F.Paste" "F.Mask")
      (net 1 "GND") (pinfunction "D55") (pintype "passive"))
    (pad "D56" smd circle (at -16.193 1.749 270) (size 0.356 0.356) (layers "F.Cu" "F.Paste" "F.Mask")
      (net 633 "/Xilinx K26 SOM/HDC03") (pinfunction "D56") (pintype "passive"))
    (pad "D57" smd circle (at -16.828 1.749 270) (size 0.356 0.356) (layers "F.Cu" "F.Paste" "F.Mask")
      (net 634 "/Xilinx K26 SOM/HDC04") (pinfunction "D57") (pintype "passive"))
    (pad "D58" smd circle (at -17.463 1.749 270) (size 0.356 0.356) (layers "F.Cu" "F.Paste" "F.Mask")
      (net 635 "/Xilinx K26 SOM/HDC05") (pinfunction "D58") (pintype "passive"))
    (pad "D59" smd circle (at -18.098 1.749 270) (size 0.356 0.356) (layers "F.Cu" "F.Paste" "F.Mask")
      (net 636 "/Xilinx K26 SOM/VCCO_HDC_1") (pinfunction "D59") (pintype "passive"))
    (pad "D60" smd circle (at -18.733 1.749 270) (size 0.356 0.356) (layers "F.Cu" "F.Paste" "F.Mask")
      (net 637 "/Xilinx K26 SOM/VCCO_HDC_2") (pinfunction "D60") (pintype "passive"))
  )
)
